# SCM (Grand Teton) — schematic netlist excerpt (pin names and nets, part order shuffled) for the footprints in the layout excerpt that follows; sources: Cadence DE-HDL packaged netlist, KiCad conversion of 12092022_DA0F0TMDCD0_F0T_Management_Board_D_brd_V3_OCP.brd

R635  Q_RES  33.2 1% CHIP  pkg 0402LF  page 36 : A = RST_WDTRST_PLD_N ; B = RST_WDTRST_PLD_R2_N
R492  Q_RES  4.7K 1% CHIP  pkg 0402LF  page 45 : A = P3V3_AUX ; B = SPI_PCH_IO3_FLASH_R1

(kicad_pcb
	(version 20260206)
	(generator "pcbnew")
	(generator_version "10.0")
	(general
		(thickness 1.6)
		(legacy_teardrops no)
	)
	(paper "A4")
	(title_block
		(title "12092022_DA0F0TMDCD0_F0T_Management_Board_D_brd_V3_OCP.brd")
		(comment 1 "Grand Teton / footprints 258-259 of 1440")
	)
	(layers
		(0 "F.Cu" signal "TOP")
		(4 "In1.Cu" signal "GND")
		(6 "In2.Cu" signal "IN1")
		(8 "In3.Cu" signal "GND1")
		(10 "In4.Cu" signal "IN2")
		(12 "In5.Cu" signal "VCC")
		(14 "In6.Cu" signal "VCC1")
		(16 "In7.Cu" signal "IN3")
		(18 "In8.Cu" signal "GND2")
		(20 "In9.Cu" signal "IN4")
		(22 "In10.Cu" signal "GND3")
		(2 "B.Cu" signal "BOTTOM")
		(9 "F.Adhes" user "F.Adhesive")
		(11 "B.Adhes" user "B.Adhesive")
		(13 "F.Paste" user "Package Geometry/Pastemask Top")
		(15 "B.Paste" user "Package Geometry/Pastemask Bottom")
		(5 "F.SilkS" user "Ref Des/Silkscreen Top")
		(7 "B.SilkS" user "Ref Des/Silkscreen Bottom")
		(1 "F.Mask" user "Board Geometry/Soldermask Top")
		(3 "B.Mask" user "Board Geometry/Soldermask Bottom")
		(17 "Dwgs.User" user "User.Drawings")
		(19 "Cmts.User" user "User.Comments")
		(21 "Eco1.User" user "User.Eco1")
		(23 "Eco2.User" user "User.Eco2")
		(25 "Edge.Cuts" user "Board Geometry/Outline")
		(27 "Margin" user)
		(31 "F.CrtYd" user "Package Geometry/Place Bound Top")
		(29 "B.CrtYd" user "Package Geometry/Place Bound Bottom")
		(35 "F.Fab" user "Ref Des/Assembly Top")
		(33 "B.Fab" user "Ref Des/Assembly Bottom")
	)
	(footprint ""
		(layer "F.Cu")
		(at 35.1536 -88.4682 180)
		(property "Reference" "R492"
			(at 0 0 180)
			(layer "F.SilkS")
			(hide yes)
			(effects
				(font
					(size 1.27 1.27)
				)
			)
		)
		(property "Value" ""
			(at 0 0 180)
			(layer "F.Fab")
			(effects
				(font
					(size 1.27 1.27)
				)
			)
		)
		(duplicate_pad_numbers_are_jumpers no)
		(fp_line
			(start 0.7874 0.4064)
			(end -0.7874 0.4064)
			(stroke
				(width 0.1524)
				(type default)
			)
			(layer "F.SilkS")
		)
		(fp_line
			(start 0.7874 -0.4064)
			(end 0.7874 0.4064)
			(stroke
				(width 0.1524)
				(type default)
			)
			(layer "F.SilkS")
		)
		(fp_line
			(start -0.7874 0.4064)
			(end -0.7874 -0.4064)
			(stroke
				(width 0.1524)
				(type default)
			)
			(layer "F.SilkS")
		)
		(fp_line
			(start -0.7874 -0.4064)
			(end 0.7874 -0.4064)
			(stroke
				(width 0.1524)
				(type default)
			)
			(layer "F.SilkS")
		)
		(fp_line
			(start 0.67945 0.3048)
			(end 0.120396 0.3048)
			(stroke
				(width 0.1)
				(type default)
			)
			(layer "F.Fab")
		)
		(fp_line
			(start 0.67945 -0.3048)
			(end 0.67945 0.3048)
			(stroke
				(width 0.1)
				(type default)
			)
			(layer "F.Fab")
		)
		(fp_line
			(start 0.12065 -0.2794)
			(end 0.12065 -0.3048)
			(stroke
				(width 0.1)
				(type default)
			)
			(layer "F.Fab")
		)
		(fp_line
			(start 0.12065 -0.3048)
			(end 0.67945 -0.3048)
			(stroke
				(width 0.1)
				(type default)
			)
			(layer "F.Fab")
		)
		(fp_line
			(start 0.120396 0.3048)
			(end 0.120396 0.2794)
			(stroke
				(width 0.1)
				(type default)
			)
			(layer "F.Fab")
		)
		(fp_line
			(start 0.120396 0.2794)
			(end -0.12065 0.2794)
			(stroke
				(width 0.1)
				(type default)
			)
			(layer "F.Fab")
		)
		(fp_line
			(start -0.12065 0.3048)
			(end -0.67945 0.3048)
			(stroke
				(width 0.1)
				(type default)
			)
			(layer "F.Fab")
		)
		(fp_line
			(start -0.12065 0.2794)
			(end -0.12065 0.3048)
			(stroke
				(width 0.1)
				(type default)
			)
			(layer "F.Fab")
		)
		(fp_line
			(start -0.12065 -0.2794)
			(end 0.12065 -0.2794)
			(stroke
				(width 0.1)
				(type default)
			)
			(layer "F.Fab")
		)
		(fp_line
			(start -0.12065 -0.305054)
			(end -0.12065 -0.2794)
			(stroke
				(width 0.1)
				(type default)
			)
			(layer "F.Fab")
		)
		(fp_line
			(start -0.67945 0.3048)
			(end -0.67945 -0.305054)
			(stroke
				(width 0.1)
				(type default)
			)
			(layer "F.Fab")
		)
		(fp_line
			(start -0.67945 -0.305054)
			(end -0.12065 -0.305054)
			(stroke
				(width 0.1)
				(type default)
			)
			(layer "F.Fab")
		)
		(pad "1" smd circle
			(at -0.40005 0 180)
			(size 0 0)
			(layers "F.Cu" "F.Mask" "F.Paste")
			(net "P3V3_AUX")
		)
		(pad "2" smd circle
			(at 0.40005 0 180)
			(size 0 0)
			(layers "F.Cu" "F.Mask" "F.Paste")
			(net "SPI_PCH_IO3_FLASH_R1")
		)
	)
	(footprint ""
		(layer "F.Cu")
		(at 26.543 -102.743 -90)
		(property "Reference" "R635"
			(at 0 0 270)
			(layer "F.SilkS")
			(hide yes)
			(effects
				(font
					(size 1.27 1.27)
				)
			)
		)
		(property "Value" ""
			(at 0 0 270)
			(layer "F.Fab")
			(effects
				(font
					(size 1.27 1.27)
				)
			)
		)
		(duplicate_pad_numbers_are_jumpers no)
		(fp_line
			(start -0.7874 0.4064)
			(end -0.7874 -0.4064)
			(stroke
				(width 0.1524)
				(type default)
			)
			(layer "F.SilkS")
		)
		(fp_line
			(start 0.7874 0.4064)
			(end -0.7874 0.4064)
			(stroke
				(width 0.1524)
				(type default)
			)
			(layer "F.SilkS")
		)
		(fp_line
			(start -0.7874 -0.4064)
			(end 0.7874 -0.4064)
			(stroke
				(width 0.1524)
				(type default)
			)
			(layer "F.SilkS")
		)
		(fp_line
			(start 0.7874 -0.4064)
			(end 0.7874 0.4064)
			(stroke
				(width 0.1524)
				(type default)
			)
			(layer "F.SilkS")
		)
		(fp_line
			(start -0.67945 0.3048)
			(end -0.67945 -0.305054)
			(stroke
				(width 0.1)
				(type default)
			)
			(layer "F.Fab")
		)
		(fp_line
			(start -0.12065 0.3048)
			(end -0.67945 0.3048)
			(stroke
				(width 0.1)
				(type default)
			)
			(layer "F.Fab")
		)
		(fp_line
			(start 0.120396 0.3048)
			(end 0.120396 0.2794)
			(stroke
				(width 0.1)
				(type default)
			)
			(layer "F.Fab")
		)
		(fp_line
			(start 0.67945 0.3048)
			(end 0.120396 0.3048)
			(stroke
				(width 0.1)
				(type default)
			)
			(layer "F.Fab")
		)
		(fp_line
			(start -0.12065 0.2794)
			(end -0.12065 0.3048)
			(stroke
				(width 0.1)
				(type default)
			)
			(layer "F.Fab")
		)
		(fp_line
			(start 0.120396 0.2794)
			(end -0.12065 0.2794)
			(stroke
				(width 0.1)
				(type default)
			)
			(layer "F.Fab")
		)
		(fp_line
			(start -0.12065 -0.2794)
			(end 0.12065 -0.2794)
			(stroke
				(width 0.1)
				(type default)
			)
			(layer "F.Fab")
		)
		(fp_line
			(start 0.12065 -0.2794)
			(end 0.12065 -0.3048)
			(stroke
				(width 0.1)
				(type default)
			)
			(layer "F.Fab")
		)
		(fp_line
			(start 0.12065 -0.3048)
			(end 0.67945 -0.3048)
			(stroke
				(width 0.1)
				(type default)
			)
			(layer "F.Fab")
		)
		(fp_line
			(start 0.67945 -0.3048)
			(end 0.67945 0.3048)
			(stroke
				(width 0.1)
				(type default)
			)
			(layer "F.Fab")
		)
		(fp_line
			(start -0.67945 -0.305054)
			(end -0.12065 -0.305054)
			(stroke
				(width 0.1)
				(type default)
			)
			(layer "F.Fab")
		)
		(fp_line
			(start -0.12065 -0.305054)
			(end -0.12065 -0.2794)
			(stroke
				(width 0.1)
				(type default)
			)
			(layer "F.Fab")
		)
		(pad "1" smd circle
			(at -0.40005 0 270)
			(size 0 0)
			(layers "F.Cu" "F.Mask" "F.Paste")
			(net "RST_WDTRST_PLD_N")
		)
		(pad "2" smd circle
			(at 0.40005 0 270)
			(size 0 0)
			(layers "F.Cu" "F.Mask" "F.Paste")
			(net "RST_WDTRST_PLD_R2_N")
		)
	)
)
